#ISCELL
  logical_power cad_note *
  *
#ISCELL
  logical_power design_note *
  *
#ISCELL
  mstr_misc dns *
  *
#ISCELL
  pure_quanta quanta_title_block_c *
  *
#ISCELL
  standard offpage *
  page297_i156
#CELL
  pure_quanta q_res *
  page297_i157
#ISCELL
  standard offpage *
  page297_i158
#CELL
  pure_quanta q_res *
  page297_i159
#ISCELL
  logical_power universal_power *
  page297_i160
#CELL
  pure_quanta 74lvc1g126se7 *
  page297_i163
#ISCELL
  logical_power universal_gnd *
  page297_i164
#CELL
  pure_quanta q_res *
  page297_i165
#ISCELL
  logical_power universal_gnd *
  page297_i166
#ISCELL
  standard offpage *
  page297_i167
#ISCELL
  logical_power universal_power *
  page297_i168
#CELL
  pure_quanta q_res *
  page297_i169
#CELL
  pure_quanta q_cap *
  page297_i170
#ISCELL
  logical_power universal_gnd *
  page297_i171
#ISCELL
  logical_power universal_power *
  page297_i172
#CELL
  pure_quanta q_cap *
  page297_i237
#ISCELL
  logical_power universal_power *
  page297_i238
#ISCELL
  standard offpage *
  page297_i240
#ISCELL
  standard offpage *
  page297_i241
#ISCELL
  logical_power universal_power *
  page297_i242
#ISCELL
  standard offpage *
  page297_i244
#CELL
  pure_quanta q_cap *
  page297_i245
#ISCELL
  logical_power universal_power *
  page297_i246
#CELL
  pure_quanta q_cap *
  page297_i247
#ISCELL
  logical_power universal_gnd *
  page297_i248
#ISCELL
  logical_power universal_gnd *
  page297_i250
#ISCELL
  standard offpage *
  page297_i251
#CELL
  pure_quanta q_cap *
  page297_i252
#ISCELL
  logical_power universal_gnd *
  page297_i253
#ISCELL
  standard offpage *
  page297_i254
#ISCELL
  standard offpage *
  page297_i255
#ISCELL
  standard offpage *
  page297_i256
#ISCELL
  standard offpage *
  page297_i257
#CELL
  pure_quanta q_cap *
  page297_i258
#ISCELL
  logical_power universal_power *
  page297_i259
#CELL
  pure_quanta q_cap *
  page297_i260
#ISCELL
  logical_power universal_power *
  page297_i261
#ISCELL
  logical_power universal_power *
  page297_i262
#ISCELL
  logical_power universal_power *
  page297_i263
#CELL
  pure_quanta q_res *
  page297_i264
#ISCELL
  standard tap *
  page297_i267
#ISCELL
  standard tap *
  page297_i268
#ISCELL
  standard tap *
  page297_i269
#ISCELL
  standard tap *
  page297_i270
#ISCELL
  standard tap *
  page297_i271
#ISCELL
  standard tap *
  page297_i272
#ISCELL
  logical_power universal_gnd *
  page297_i273
#ISCELL
  logical_power universal_gnd *
  page297_i275
#ISCELL
  standard tap *
  page297_i278
#ISCELL
  standard tap *
  page297_i280
#ISCELL
  standard tap *
  page297_i281
#ISCELL
  standard tap *
  page297_i283
#ISCELL
  standard offpage *
  page297_i285
#ISCELL
  standard offpage *
  page297_i286
#ISCELL
  standard offpage *
  page297_i287
#ISCELL
  standard offpage *
  page297_i288
#ISCELL
  standard offpage *
  page297_i289
#ISCELL
  logical_power universal_power *
  page297_i290
#CELL
  pure_quanta q_res *
  page297_i291
#ISCELL
  standard offpage *
  page297_i292
#CELL
  pure_quanta q_res *
  page297_i293
#ISCELL
  logical_power universal_gnd *
  page297_i294
#ISCELL
  logical_power universal_power *
  page297_i295
#CELL
  pure_quanta q_res *
  page297_i296
#ISCELL
  standard offpage *
  page297_i297
#ISCELL
  standard offpage *
  page297_i298
#CELL
  pure_quanta q_res *
  page297_i299
#ISCELL
  logical_power universal_power *
  page297_i300
#CELL
  pure_quanta q_res *
  page297_i301
#CELL
  pure_quanta q_res *
  page297_i302
#ISCELL
  logical_power universal_gnd *
  page297_i303
#CELL
  pure_quanta q_cap *
  page297_i304
#CELL
  pure_quanta 74lvc2g07dw7 *
  page297_i305
#ISCELL
  logical_power universal_gnd *
  page297_i306
#CELL
  pure_quanta q_res *
  page297_i307
#ISCELL
  standard offpage *
  page297_i308
#CELL
  pure_quanta q_res *
  page297_i309
#ISCELL
  standard offpage *
  page297_i310
#CELL
  pure_quanta q_res *
  page297_i311
#CELL
  pure_quanta q_res *
  page297_i312
#CELL
  pure_quanta q_res *
  page297_i313
#CELL
  pure_quanta mosfet_nch_gds_esd_protected *
  page297_i316
#ISCELL
  logical_power universal_gnd *
  page297_i317
#CELL
  pure_quanta sconn56_123276793 *
  page297_i318
#ISCELL
  standard tap *
  page297_i319
#ISCELL
  standard tap *
  page297_i320
#ISCELL
  standard tap *
  page297_i321
#ISCELL
  standard tap *
  page297_i322
#ISCELL
  standard tap *
  page297_i324
#ISCELL
  standard tap *
  page297_i325
#ISCELL
  logical_power universal_gnd *
  page297_i326
#CELL
  pure_quanta q_cap *
  page297_i327
#ISCELL
  logical_power universal_power *
  page297_i328
#CELL
  pure_quanta apx80929sag7 *
  page297_i329
#ISCELL
  logical_power universal_gnd *
  page297_i330
#CELL
  pure_quanta q_res *
  page297_i331
#ISCELL
  standard offpage *
  page297_i332
